(kicad_pcb
	(version 20260206)
	(generator "pcbnew")
	(generator_version "10.0")
	(general
		(thickness 1.6)
		(legacy_teardrops no)
	)
	(paper "A4")
	(title_block
		(title "04192023_DAF0TMB3IC0_F0TG_MB_C_brd_V02_OCP.brd")
		(comment 1 "Grand Teton / footprints 7881-7886 of 8354")
	)
	(layers
		(0 "F.Cu" signal "TOP")
		(4 "In1.Cu" signal "GND")
		(6 "In2.Cu" signal "IN1")
		(8 "In3.Cu" signal "GND1")
		(10 "In4.Cu" signal "IN2")
		(12 "In5.Cu" signal "GND2")
		(14 "In6.Cu" signal "IN3")
		(16 "In7.Cu" signal "GND3")
		(18 "In8.Cu" signal "VCC")
		(20 "In9.Cu" signal "VCC1")
		(22 "In10.Cu" signal "GND4")
		(24 "In11.Cu" signal "IN4")
		(26 "In12.Cu" signal "GND5")
		(28 "In13.Cu" signal "IN5")
		(30 "In14.Cu" signal "GND6")
		(32 "In15.Cu" signal "IN6")
		(34 "In16.Cu" signal "GND7")
		(2 "B.Cu" signal "BOTTOM")
		(9 "F.Adhes" user "F.Adhesive")
		(11 "B.Adhes" user "B.Adhesive")
		(13 "F.Paste" user "Package Geometry/Pastemask Top")
		(15 "B.Paste" user "Package Geometry/Pastemask Bottom")
		(5 "F.SilkS" user "Ref Des/Silkscreen Top")
		(7 "B.SilkS" user "Ref Des/Silkscreen Bottom")
		(1 "F.Mask" user "Board Geometry/Soldermask Top")
		(3 "B.Mask" user "Board Geometry/Soldermask Bottom")
		(17 "Dwgs.User" user "User.Drawings")
		(19 "Cmts.User" user "User.Comments")
		(21 "Eco1.User" user "User.Eco1")
		(23 "Eco2.User" user "User.Eco2")
		(25 "Edge.Cuts" user "Board Geometry/Outline")
		(27 "Margin" user)
		(31 "F.CrtYd" user "Package Geometry/Place Bound Top")
		(29 "B.CrtYd" user "Package Geometry/Place Bound Bottom")
		(35 "F.Fab" user "Ref Des/Assembly Top")
		(33 "B.Fab" user "Ref Des/Assembly Bottom")
	)
	(footprint ""
		(layer "B.Cu")
		(at 362.267246 -261.747762 90)
		(property "Reference" "C2634"
			(at 0 0 90)
			(layer "B.SilkS")
			(hide yes)
			(effects
				(font
					(size 1.27 1.27)
				)
				(justify mirror)
			)
		)
		(property "Value" ""
			(at 0 0 90)
			(layer "B.Fab")
			(effects
				(font
					(size 1.27 1.27)
				)
				(justify mirror)
			)
		)
		(duplicate_pad_numbers_are_jumpers no)
		(fp_line
			(start 0.7874 -0.4064)
			(end -0.7874 -0.4064)
			(stroke
				(width 0.1524)
				(type default)
			)
			(layer "B.SilkS")
		)
		(fp_line
			(start -0.7874 -0.4064)
			(end -0.7874 0.4064)
			(stroke
				(width 0.1524)
				(type default)
			)
			(layer "B.SilkS")
		)
		(fp_line
			(start 0.7874 0.4064)
			(end 0.7874 -0.4064)
			(stroke
				(width 0.1524)
				(type default)
			)
			(layer "B.SilkS")
		)
		(fp_line
			(start -0.7874 0.4064)
			(end 0.7874 0.4064)
			(stroke
				(width 0.1524)
				(type default)
			)
			(layer "B.SilkS")
		)
		(fp_line
			(start 0.67945 -0.305054)
			(end 0.12065 -0.305054)
			(stroke
				(width 0.1)
				(type default)
			)
			(layer "B.Fab")
		)
		(fp_line
			(start 0.12065 -0.305054)
			(end 0.12065 -0.2794)
			(stroke
				(width 0.1)
				(type default)
			)
			(layer "B.Fab")
		)
		(fp_line
			(start -0.12065 -0.3048)
			(end -0.67945 -0.3048)
			(stroke
				(width 0.1)
				(type default)
			)
			(layer "B.Fab")
		)
		(fp_line
			(start -0.67945 -0.3048)
			(end -0.67945 0.3048)
			(stroke
				(width 0.1)
				(type default)
			)
			(layer "B.Fab")
		)
		(fp_line
			(start 0.12065 -0.2794)
			(end -0.12065 -0.2794)
			(stroke
				(width 0.1)
				(type default)
			)
			(layer "B.Fab")
		)
		(fp_line
			(start -0.12065 -0.2794)
			(end -0.12065 -0.3048)
			(stroke
				(width 0.1)
				(type default)
			)
			(layer "B.Fab")
		)
		(fp_line
			(start 0.12065 0.2794)
			(end 0.12065 0.3048)
			(stroke
				(width 0.1)
				(type default)
			)
			(layer "B.Fab")
		)
		(fp_line
			(start -0.120396 0.2794)
			(end 0.12065 0.2794)
			(stroke
				(width 0.1)
				(type default)
			)
			(layer "B.Fab")
		)
		(fp_line
			(start 0.67945 0.3048)
			(end 0.67945 -0.305054)
			(stroke
				(width 0.1)
				(type default)
			)
			(layer "B.Fab")
		)
		(fp_line
			(start 0.12065 0.3048)
			(end 0.67945 0.3048)
			(stroke
				(width 0.1)
				(type default)
			)
			(layer "B.Fab")
		)
		(fp_line
			(start -0.120396 0.3048)
			(end -0.120396 0.2794)
			(stroke
				(width 0.1)
				(type default)
			)
			(layer "B.Fab")
		)
		(fp_line
			(start -0.67945 0.3048)
			(end -0.120396 0.3048)
			(stroke
				(width 0.1)
				(type default)
			)
			(layer "B.Fab")
		)
		(pad "1" smd circle
			(at 0.40005 0 270)
			(size 0 0)
			(layers "B.Cu" "B.Mask" "B.Paste")
			(net "PVDD11_S3_P0")
		)
		(pad "2" smd circle
			(at -0.40005 0 270)
			(size 0 0)
			(layers "B.Cu" "B.Mask" "B.Paste")
			(net "GND")
		)
	)
	(footprint ""
		(layer "B.Cu")
		(at 20.32 -367.919)
		(property "Reference" "R1496"
			(at 0 0 0)
			(layer "B.SilkS")
			(hide yes)
			(effects
				(font
					(size 1.27 1.27)
				)
				(justify mirror)
			)
		)
		(property "Value" ""
			(at 0 0 0)
			(layer "B.Fab")
			(effects
				(font
					(size 1.27 1.27)
				)
				(justify mirror)
			)
		)
		(duplicate_pad_numbers_are_jumpers no)
		(fp_line
			(start -0.7874 -0.4064)
			(end -0.7874 0.4064)
			(stroke
				(width 0.1524)
				(type default)
			)
			(layer "B.SilkS")
		)
		(fp_line
			(start -0.7874 0.4064)
			(end 0.7874 0.4064)
			(stroke
				(width 0.1524)
				(type default)
			)
			(layer "B.SilkS")
		)
		(fp_line
			(start 0.7874 -0.4064)
			(end -0.7874 -0.4064)
			(stroke
				(width 0.1524)
				(type default)
			)
			(layer "B.SilkS")
		)
		(fp_line
			(start 0.7874 0.4064)
			(end 0.7874 -0.4064)
			(stroke
				(width 0.1524)
				(type default)
			)
			(layer "B.SilkS")
		)
		(fp_line
			(start -0.67945 -0.3048)
			(end -0.67945 0.3048)
			(stroke
				(width 0.1)
				(type default)
			)
			(layer "B.Fab")
		)
		(fp_line
			(start -0.67945 0.3048)
			(end -0.120396 0.3048)
			(stroke
				(width 0.1)
				(type default)
			)
			(layer "B.Fab")
		)
		(fp_line
			(start -0.12065 -0.3048)
			(end -0.67945 -0.3048)
			(stroke
				(width 0.1)
				(type default)
			)
			(layer "B.Fab")
		)
		(fp_line
			(start -0.12065 -0.2794)
			(end -0.12065 -0.3048)
			(stroke
				(width 0.1)
				(type default)
			)
			(layer "B.Fab")
		)
		(fp_line
			(start -0.120396 0.2794)
			(end 0.12065 0.2794)
			(stroke
				(width 0.1)
				(type default)
			)
			(layer "B.Fab")
		)
		(fp_line
			(start -0.120396 0.3048)
			(end -0.120396 0.2794)
			(stroke
				(width 0.1)
				(type default)
			)
			(layer "B.Fab")
		)
		(fp_line
			(start 0.12065 -0.305054)
			(end 0.12065 -0.2794)
			(stroke
				(width 0.1)
				(type default)
			)
			(layer "B.Fab")
		)
		(fp_line
			(start 0.12065 -0.2794)
			(end -0.12065 -0.2794)
			(stroke
				(width 0.1)
				(type default)
			)
			(layer "B.Fab")
		)
		(fp_line
			(start 0.12065 0.2794)
			(end 0.12065 0.3048)
			(stroke
				(width 0.1)
				(type default)
			)
			(layer "B.Fab")
		)
		(fp_line
			(start 0.12065 0.3048)
			(end 0.67945 0.3048)
			(stroke
				(width 0.1)
				(type default)
			)
			(layer "B.Fab")
		)
		(fp_line
			(start 0.67945 -0.305054)
			(end 0.12065 -0.305054)
			(stroke
				(width 0.1)
				(type default)
			)
			(layer "B.Fab")
		)
		(fp_line
			(start 0.67945 0.3048)
			(end 0.67945 -0.305054)
			(stroke
				(width 0.1)
				(type default)
			)
			(layer "B.Fab")
		)
		(pad "1" smd circle
			(at 0.40005 0 180)
			(size 0 0)
			(layers "B.Cu" "B.Mask" "B.Paste")
			(net "SMB_SCM_2_R1_SDA")
		)
		(pad "2" smd circle
			(at -0.40005 0 180)
			(size 0 0)
			(layers "B.Cu" "B.Mask" "B.Paste")
			(net "SMB_SCM_2_R2_SDA")
		)
	)
	(footprint ""
		(layer "B.Cu")
		(at 77.783944 -408.517344 90)
		(property "Reference" "C6679"
			(at 0 0 90)
			(layer "B.SilkS")
			(hide yes)
			(effects
				(font
					(size 1.27 1.27)
				)
				(justify mirror)
			)
		)
		(property "Value" ""
			(at 0 0 90)
			(layer "B.Fab")
			(effects
				(font
					(size 1.27 1.27)
				)
				(justify mirror)
			)
		)
		(duplicate_pad_numbers_are_jumpers no)
		(fp_line
			(start 0.299974 -0.150114)
			(end -0.299974 -0.150114)
			(stroke
				(width 0.1)
				(type default)
			)
			(layer "B.Fab")
		)
		(fp_line
			(start -0.299974 -0.150114)
			(end -0.299974 0.150114)
			(stroke
				(width 0.1)
				(type default)
			)
			(layer "B.Fab")
		)
		(fp_line
			(start 0.299974 0.150114)
			(end 0.299974 -0.150114)
			(stroke
				(width 0.1)
				(type default)
			)
			(layer "B.Fab")
		)
		(fp_line
			(start -0.299974 0.150114)
			(end 0.299974 0.150114)
			(stroke
				(width 0.1)
				(type default)
			)
			(layer "B.Fab")
		)
		(pad "1" smd rect
			(at 0.2667 0 270)
			(size 0.3048 0.381)
			(layers "B.Cu" "B.Mask" "B.Paste")
			(net "P5E_CPU1_P1_TX_BUF_C_DP<9>")
		)
		(pad "2" smd rect
			(at -0.2667 0 270)
			(size 0.3048 0.381)
			(layers "B.Cu" "B.Mask" "B.Paste")
			(net "P5E_CPU1_P1_TX_BUF_DP<9>")
		)
	)
	(footprint ""
		(layer "B.Cu")
		(at 318.539876 -66.708782 90)
		(property "Reference" "R3071"
			(at 0 0 90)
			(layer "B.SilkS")
			(hide yes)
			(effects
				(font
					(size 1.27 1.27)
				)
				(justify mirror)
			)
		)
		(property "Value" ""
			(at 0 0 90)
			(layer "B.Fab")
			(effects
				(font
					(size 1.27 1.27)
				)
				(justify mirror)
			)
		)
		(duplicate_pad_numbers_are_jumpers no)
		(fp_line
			(start 0.7874 -0.4064)
			(end -0.7874 -0.4064)
			(stroke
				(width 0.1524)
				(type default)
			)
			(layer "B.SilkS")
		)
		(fp_line
			(start -0.7874 -0.4064)
			(end -0.7874 0.4064)
			(stroke
				(width 0.1524)
				(type default)
			)
			(layer "B.SilkS")
		)
		(fp_line
			(start 0.7874 0.4064)
			(end 0.7874 -0.4064)
			(stroke
				(width 0.1524)
				(type default)
			)
			(layer "B.SilkS")
		)
		(fp_line
			(start -0.7874 0.4064)
			(end 0.7874 0.4064)
			(stroke
				(width 0.1524)
				(type default)
			)
			(layer "B.SilkS")
		)
		(fp_line
			(start 0.67945 -0.305054)
			(end 0.12065 -0.305054)
			(stroke
				(width 0.1)
				(type default)
			)
			(layer "B.Fab")
		)
		(fp_line
			(start 0.12065 -0.305054)
			(end 0.12065 -0.2794)
			(stroke
				(width 0.1)
				(type default)
			)
			(layer "B.Fab")
		)
		(fp_line
			(start -0.12065 -0.3048)
			(end -0.67945 -0.3048)
			(stroke
				(width 0.1)
				(type default)
			)
			(layer "B.Fab")
		)
		(fp_line
			(start -0.67945 -0.3048)
			(end -0.67945 0.3048)
			(stroke
				(width 0.1)
				(type default)
			)
			(layer "B.Fab")
		)
		(fp_line
			(start 0.12065 -0.2794)
			(end -0.12065 -0.2794)
			(stroke
				(width 0.1)
				(type default)
			)
			(layer "B.Fab")
		)
		(fp_line
			(start -0.12065 -0.2794)
			(end -0.12065 -0.3048)
			(stroke
				(width 0.1)
				(type default)
			)
			(layer "B.Fab")
		)
		(fp_line
			(start 0.12065 0.2794)
			(end 0.12065 0.3048)
			(stroke
				(width 0.1)
				(type default)
			)
			(layer "B.Fab")
		)
		(fp_line
			(start -0.120396 0.2794)
			(end 0.12065 0.2794)
			(stroke
				(width 0.1)
				(type default)
			)
			(layer "B.Fab")
		)
		(fp_line
			(start 0.67945 0.3048)
			(end 0.67945 -0.305054)
			(stroke
				(width 0.1)
				(type default)
			)
			(layer "B.Fab")
		)
		(fp_line
			(start 0.12065 0.3048)
			(end 0.67945 0.3048)
			(stroke
				(width 0.1)
				(type default)
			)
			(layer "B.Fab")
		)
		(fp_line
			(start -0.120396 0.3048)
			(end -0.120396 0.2794)
			(stroke
				(width 0.1)
				(type default)
			)
			(layer "B.Fab")
		)
		(fp_line
			(start -0.67945 0.3048)
			(end -0.120396 0.3048)
			(stroke
				(width 0.1)
				(type default)
			)
			(layer "B.Fab")
		)
		(pad "1" smd circle
			(at 0.40005 0 270)
			(size 0 0)
			(layers "B.Cu" "B.Mask" "B.Paste")
			(net "LED_PWRGD_P1V8_AUX")
		)
		(pad "2" smd circle
			(at -0.40005 0 270)
			(size 0 0)
			(layers "B.Cu" "B.Mask" "B.Paste")
			(net "P3V3_AUX")
		)
	)
	(footprint ""
		(layer "B.Cu")
		(at 490.160564 -457.29144 -90)
		(property "Reference" "X9026"
			(at 4.7244 -1.61163 270)
			(unlocked yes)
			(layer "B.SilkS")
			(effects
				(font
					(size 0.7874 0.5842)
					(thickness 0.1524)
				)
				(justify left mirror)
			)
		)
		(property "Value" ""
			(at 0 0 90)
			(layer "B.Fab")
			(effects
				(font
					(size 1.27 1.27)
				)
				(justify mirror)
			)
		)
		(property "User Part Number" "N_A"
			(at -1.30175 1.27 180)
			(unlocked yes)
			(layer "Cmts.User")
			(hide yes)
			(effects
				(font
					(size 0.635 0.4064)
					(thickness 0.1524)
				)
				(justify mirror)
			)
		)
		(property "Device Type" "TP_TDR_4P_FTS_TH-TP_TDR_4P_DIP,EMPTY,TP15"
			(at -1.30175 1.27 180)
			(unlocked yes)
			(layer "B.Fab")
			(hide yes)
			(effects
				(font
					(size 0.635 0.4064)
					(thickness 0.1524)
				)
				(justify mirror)
			)
		)
		(duplicate_pad_numbers_are_jumpers no)
		(fp_line
			(start -2.54 3.81)
			(end -2.54 3.6703)
			(stroke
				(width 0.1524)
				(type default)
			)
			(layer "B.SilkS")
		)
		(fp_line
			(start 0 3.81)
			(end -2.54 3.81)
			(stroke
				(width 0.1524)
				(type default)
			)
			(layer "B.SilkS")
		)
		(fp_line
			(start 0 3.175)
			(end 0 3.81)
			(stroke
				(width 0.1524)
				(type default)
			)
			(layer "B.SilkS")
		)
		(fp_line
			(start -2.54 1.4097)
			(end -2.54 1.1303)
			(stroke
				(width 0.1524)
				(type default)
			)
			(layer "B.SilkS")
		)
		(fp_line
			(start 0 0.635)
			(end 0 1.905)
			(stroke
				(width 0.1524)
				(type default)
			)
			(layer "B.SilkS")
		)
		(fp_line
			(start -2.54 -1.1303)
			(end -2.54 -1.27)
			(stroke
				(width 0.1524)
				(type default)
			)
			(layer "B.SilkS")
		)
		(fp_line
			(start -2.54 -1.27)
			(end 0 -1.27)
			(stroke
				(width 0.1524)
				(type default)
			)
			(layer "B.SilkS")
		)
		(fp_line
			(start 0 -1.27)
			(end 0 -0.635)
			(stroke
				(width 0.1524)
				(type default)
			)
			(layer "B.SilkS")
		)
		(fp_poly
			(pts
				(xy 0.761746 0) (xy 2.285746 -0.762) (xy 2.285746 0.762)
			)
			(stroke
				(width 0)
				(type default)
			)
			(fill yes)
			(layer "B.SilkS")
		)
		(fp_line
			(start -2.54 3.81)
			(end -2.54 -1.27)
			(stroke
				(width 0.1)
				(type default)
			)
			(layer "B.Fab")
		)
		(fp_line
			(start 0 3.81)
			(end -2.54 3.81)
			(stroke
				(width 0.1)
				(type default)
			)
			(layer "B.Fab")
		)
		(fp_line
			(start -2.54 -1.27)
			(end 0 -1.27)
			(stroke
				(width 0.1)
				(type default)
			)
			(layer "B.Fab")
		)
		(fp_line
			(start 0 -1.27)
			(end 0 3.81)
			(stroke
				(width 0.1)
				(type default)
			)
			(layer "B.Fab")
		)
		(fp_poly
			(pts
				(xy 0.761746 0) (xy 2.285746 -0.762) (xy 2.285746 0.762)
			)
			(stroke
				(width 0)
				(type default)
			)
			(fill yes)
			(layer "B.Fab")
		)
		(pad "1" thru_hole circle
			(at 0 0 90)
			(size 1.0033 1.0033)
			(drill 0.249936)
			(layers "*.Cu" "*.Mask")
			(remove_unused_layers no)
			(net "TDR_DIFF_85_NECK_IN6_DP")
			(clearance 0.10795)
			(padstack
				(mode front_inner_back)
				(layer "Inner"
					(shape circle)
					(size 0.8001 0.8001)
					(clearance 0.1524)
				)
				(layer "B.Cu"
					(shape circle)
					(size 1.0033 1.0033)
					(thermal_gap 0.10795)
					(clearance 0.10795)
				)
			)
		)
		(pad "2" thru_hole circle
			(at -2.54 0 90)
			(size 1.9939 1.9939)
			(drill 0.249936)
			(layers "*.Cu" "*.Mask")
			(remove_unused_layers no)
			(net "T1_GND")
			(clearance 0.10795)
			(padstack
				(mode front_inner_back)
				(layer "Inner"
					(shape circle)
					(size 0.8001 0.8001)
					(clearance 0.1524)
				)
				(layer "B.Cu"
					(shape circle)
					(size 1.9939 1.9939)
					(thermal_gap 0.10795)
					(clearance 0.10795)
				)
			)
		)
		(pad "3" thru_hole circle
			(at -2.54 2.54 90)
			(size 1.9939 1.9939)
			(drill 0.249936)
			(layers "*.Cu" "*.Mask")
			(remove_unused_layers no)
			(net "T1_GND")
			(clearance 0.10795)
			(padstack
				(mode front_inner_back)
				(layer "Inner"
					(shape circle)
					(size 0.8001 0.8001)
					(clearance 0.1524)
				)
				(layer "B.Cu"
					(shape circle)
					(size 1.9939 1.9939)
					(thermal_gap 0.10795)
					(clearance 0.10795)
				)
			)
		)
		(pad "4" thru_hole circle
			(at 0 2.54 90)
			(size 1.0033 1.0033)
			(drill 0.249936)
			(layers "*.Cu" "*.Mask")
			(remove_unused_layers no)
			(net "TDR_DIFF_85_NECK_IN6_DN")
			(clearance 0.10795)
			(padstack
				(mode front_inner_back)
				(layer "Inner"
					(shape circle)
					(size 0.8001 0.8001)
					(clearance 0.1524)
				)
				(layer "B.Cu"
					(shape circle)
					(size 1.0033 1.0033)
					(thermal_gap 0.10795)
					(clearance 0.10795)
				)
			)
		)
	)
	(footprint ""
		(layer "B.Cu")
		(at 197.269608 -106.513376)
		(property "Reference" "R289"
			(at 0 0 0)
			(layer "B.SilkS")
			(hide yes)
			(effects
				(font
					(size 1.27 1.27)
				)
				(justify mirror)
			)
		)
		(property "Value" ""
			(at 0 0 0)
			(layer "B.Fab")
			(effects
				(font
					(size 1.27 1.27)
				)
				(justify mirror)
			)
		)
		(duplicate_pad_numbers_are_jumpers no)
		(fp_line
			(start -0.7874 -0.4064)
			(end -0.7874 0.4064)
			(stroke
				(width 0.1524)
				(type default)
			)
			(layer "B.SilkS")
		)
		(fp_line
			(start -0.7874 0.4064)
			(end 0.7874 0.4064)
			(stroke
				(width 0.1524)
				(type default)
			)
			(layer "B.SilkS")
		)
		(fp_line
			(start 0.7874 -0.4064)
			(end -0.7874 -0.4064)
			(stroke
				(width 0.1524)
				(type default)
			)
			(layer "B.SilkS")
		)
		(fp_line
			(start 0.7874 0.4064)
			(end 0.7874 -0.4064)
			(stroke
				(width 0.1524)
				(type default)
			)
			(layer "B.SilkS")
		)
		(fp_line
			(start -0.67945 -0.3048)
			(end -0.67945 0.3048)
			(stroke
				(width 0.1)
				(type default)
			)
			(layer "B.Fab")
		)
		(fp_line
			(start -0.67945 0.3048)
			(end -0.120396 0.3048)
			(stroke
				(width 0.1)
				(type default)
			)
			(layer "B.Fab")
		)
		(fp_line
			(start -0.12065 -0.3048)
			(end -0.67945 -0.3048)
			(stroke
				(width 0.1)
				(type default)
			)
			(layer "B.Fab")
		)
		(fp_line
			(start -0.12065 -0.2794)
			(end -0.12065 -0.3048)
			(stroke
				(width 0.1)
				(type default)
			)
			(layer "B.Fab")
		)
		(fp_line
			(start -0.120396 0.2794)
			(end 0.12065 0.2794)
			(stroke
				(width 0.1)
				(type default)
			)
			(layer "B.Fab")
		)
		(fp_line
			(start -0.120396 0.3048)
			(end -0.120396 0.2794)
			(stroke
				(width 0.1)
				(type default)
			)
			(layer "B.Fab")
		)
		(fp_line
			(start 0.12065 -0.305054)
			(end 0.12065 -0.2794)
			(stroke
				(width 0.1)
				(type default)
			)
			(layer "B.Fab")
		)
		(fp_line
			(start 0.12065 -0.2794)
			(end -0.12065 -0.2794)
			(stroke
				(width 0.1)
				(type default)
			)
			(layer "B.Fab")
		)
		(fp_line
			(start 0.12065 0.2794)
			(end 0.12065 0.3048)
			(stroke
				(width 0.1)
				(type default)
			)
			(layer "B.Fab")
		)
		(fp_line
			(start 0.12065 0.3048)
			(end 0.67945 0.3048)
			(stroke
				(width 0.1)
				(type default)
			)
			(layer "B.Fab")
		)
		(fp_line
			(start 0.67945 -0.305054)
			(end 0.12065 -0.305054)
			(stroke
				(width 0.1)
				(type default)
			)
			(layer "B.Fab")
		)
		(fp_line
			(start 0.67945 0.3048)
			(end 0.67945 -0.305054)
			(stroke
				(width 0.1)
				(type default)
			)
			(layer "B.Fab")
		)
		(pad "1" smd circle
			(at 0.40005 0 180)
			(size 0 0)
			(layers "B.Cu" "B.Mask" "B.Paste")
			(net "PVDD18_S5_P1_EN")
		)
		(pad "2" smd circle
			(at -0.40005 0 180)
			(size 0 0)
			(layers "B.Cu" "B.Mask" "B.Paste")
			(net "PVDD18_S5_P1_R_EN")
		)
	)
)
